(kicad_pcb
	(version 20260206)
	(generator "pcbnew")
	(generator_version "10.0")
	(general
		(thickness 1.6)
		(legacy_teardrops no)
	)
	(paper "A4")
	(title_block
		(title "panther-plus-userver — 13130-1b_20150205.brd")
		(comment 1 "Honey Badger (Wiwynn) / footprints 1143-1150 of 1509")
	)
	(layers
		(0 "F.Cu" signal "TOP")
		(4 "In1.Cu" signal "L2")
		(6 "In2.Cu" signal "L3")
		(8 "In3.Cu" signal "L4")
		(10 "In4.Cu" signal "L5")
		(12 "In5.Cu" signal "L6")
		(14 "In6.Cu" signal "L7")
		(16 "In7.Cu" signal "L8")
		(18 "In8.Cu" signal "L9")
		(20 "In9.Cu" signal "L10")
		(22 "In10.Cu" signal "L11")
		(2 "B.Cu" signal "BOTTOM")
		(9 "F.Adhes" user "F.Adhesive")
		(11 "B.Adhes" user "B.Adhesive")
		(13 "F.Paste" user "Package Geometry/Pastemask Top")
		(15 "B.Paste" user "Package Geometry/Pastemask Bottom")
		(5 "F.SilkS" user "Ref Des/Silkscreen Top")
		(7 "B.SilkS" user "Ref Des/Silkscreen Bottom")
		(1 "F.Mask" user "Board Geometry/Soldermask Top")
		(3 "B.Mask" user "Board Geometry/Soldermask Bottom")
		(17 "Dwgs.User" user "User.Drawings")
		(19 "Cmts.User" user "User.Comments")
		(21 "Eco1.User" user "User.Eco1")
		(23 "Eco2.User" user "User.Eco2")
		(25 "Edge.Cuts" user "Board Geometry/Outline")
		(27 "Margin" user)
		(31 "F.CrtYd" user "Package Geometry/Place Bound Top")
		(29 "B.CrtYd" user "Package Geometry/Place Bound Bottom")
		(35 "F.Fab" user "Ref Des/Assembly Top")
		(33 "B.Fab" user "Ref Des/Assembly Bottom")
	)
	(footprint ""
		(layer "B.Cu")
		(at 33.7058 -47.7774)
		(property "Reference" "PC132"
			(at 0 0 0)
			(layer "B.SilkS")
			(hide yes)
			(effects
				(font
					(size 1.27 1.27)
				)
				(justify mirror)
			)
		)
		(property "Value" "SC470P50V2KX-3GP"
			(at -1.8923 -1.2065 0)
			(unlocked yes)
			(layer "B.Fab")
			(hide yes)
			(effects
				(font
					(size 1.016 1.016)
					(thickness 0.1524)
				)
				(justify mirror)
			)
		)
		(property "Device Type" "C402H22"
			(at -1.8923 -2.7305 0)
			(unlocked yes)
			(layer "B.Fab")
			(hide yes)
			(effects
				(font
					(size 1.016 1.016)
					(thickness 0.1524)
				)
				(justify mirror)
			)
		)
		(duplicate_pad_numbers_are_jumpers no)
		(fp_rect
			(start 0.381 0.7366)
			(end -0.381 -0.7366)
			(stroke
				(width 0)
				(type default)
			)
			(fill no)
			(layer "B.CrtYd")
		)
		(fp_rect
			(start 0.381 0.7366)
			(end -0.381 -0.7366)
			(stroke
				(width 0)
				(type default)
			)
			(fill no)
			(layer "B.Fab")
		)
		(pad "1" smd custom
			(at 0 -0.4572 180)
			(size 0.1143 0.1143)
			(layers "B.Cu" "B.Mask" "B.Paste")
			(net "GND")
			(options
				(clearance outline)
				(anchor circle)
			)
			(primitives
				(gr_poly
					(pts
						(arc
							(start -0.254 0.1778)
							(mid -0.239121 0.213721)
							(end -0.2032 0.2286)
						)
						(arc
							(start 0.2032 0.2286)
							(mid 0.239121 0.213721)
							(end 0.254 0.1778)
						)
						(arc
							(start 0.254 -0.1778)
							(mid 0.239121 -0.213721)
							(end 0.2032 -0.2286)
						)
						(arc
							(start -0.2032 -0.2286)
							(mid -0.239121 -0.213721)
							(end -0.254 -0.1778)
						)
					)
					(width 0)
					(fill yes)
				)
			)
		)
		(pad "2" smd custom
			(at 0 0.4572 180)
			(size 0.1143 0.1143)
			(layers "B.Cu" "B.Mask" "B.Paste")
			(net "P1V5_STBY_SS")
			(options
				(clearance outline)
				(anchor circle)
			)
			(primitives
				(gr_poly
					(pts
						(arc
							(start -0.254 0.1778)
							(mid -0.239121 0.213721)
							(end -0.2032 0.2286)
						)
						(arc
							(start 0.2032 0.2286)
							(mid 0.239121 0.213721)
							(end 0.254 0.1778)
						)
						(arc
							(start 0.254 -0.1778)
							(mid 0.239121 -0.213721)
							(end 0.2032 -0.2286)
						)
						(arc
							(start -0.2032 -0.2286)
							(mid -0.239121 -0.213721)
							(end -0.254 -0.1778)
						)
					)
					(width 0)
					(fill yes)
				)
			)
		)
	)
	(footprint ""
		(layer "B.Cu")
		(at 41.148 -14.605 90)
		(property "Reference" "R429"
			(at 0 0 90)
			(layer "B.SilkS")
			(hide yes)
			(effects
				(font
					(size 1.27 1.27)
				)
				(justify mirror)
			)
		)
		(property "Value" "43D2R2F-GP"
			(at -1.7907 -1.1176 90)
			(unlocked yes)
			(layer "B.Fab")
			(hide yes)
			(effects
				(font
					(size 1.016 1.016)
					(thickness 0.1524)
				)
				(justify mirror)
			)
		)
		(property "Device Type" "R402H16"
			(at -1.7907 -2.6416 90)
			(unlocked yes)
			(layer "B.Fab")
			(hide yes)
			(effects
				(font
					(size 1.016 1.016)
					(thickness 0.1524)
				)
				(justify mirror)
			)
		)
		(duplicate_pad_numbers_are_jumpers no)
		(fp_rect
			(start 0.381 0.8382)
			(end -0.381 -0.8382)
			(stroke
				(width 0)
				(type default)
			)
			(fill no)
			(layer "B.CrtYd")
		)
		(fp_rect
			(start 0.381 0.8382)
			(end -0.381 -0.8382)
			(stroke
				(width 0)
				(type default)
			)
			(fill no)
			(layer "B.Fab")
		)
		(pad "1" smd custom
			(at 0 -0.4318 270)
			(size 0.127 0.127)
			(layers "B.Cu" "B.Mask" "B.Paste")
			(net "CLK_100M_PCIE_SAS_DP")
			(options
				(clearance outline)
				(anchor circle)
			)
			(primitives
				(gr_poly
					(pts
						(arc
							(start -0.2032 0.2794)
							(mid -0.239121 0.264521)
							(end -0.254 0.2286)
						)
						(arc
							(start -0.254 -0.2286)
							(mid -0.239121 -0.264521)
							(end -0.2032 -0.2794)
						)
						(arc
							(start 0.2032 -0.2794)
							(mid 0.239121 -0.264521)
							(end 0.254 -0.2286)
						)
						(arc
							(start 0.254 0.2286)
							(mid 0.239121 0.264521)
							(end 0.2032 0.2794)
						)
					)
					(width 0)
					(fill yes)
				)
			)
		)
		(pad "2" smd custom
			(at 0 0.4318 270)
			(size 0.127 0.127)
			(layers "B.Cu" "B.Mask" "B.Paste")
			(net "GND")
			(options
				(clearance outline)
				(anchor circle)
			)
			(primitives
				(gr_poly
					(pts
						(arc
							(start -0.2032 0.2794)
							(mid -0.239121 0.264521)
							(end -0.254 0.2286)
						)
						(arc
							(start -0.254 -0.2286)
							(mid -0.239121 -0.264521)
							(end -0.2032 -0.2794)
						)
						(arc
							(start 0.2032 -0.2794)
							(mid 0.239121 -0.264521)
							(end 0.254 -0.2286)
						)
						(arc
							(start 0.254 0.2286)
							(mid 0.239121 0.264521)
							(end 0.2032 0.2794)
						)
					)
					(width 0)
					(fill yes)
				)
			)
		)
	)
	(footprint ""
		(layer "B.Cu")
		(at 40.64 -15.9004)
		(property "Reference" "R368"
			(at 0 0 0)
			(layer "B.SilkS")
			(hide yes)
			(effects
				(font
					(size 1.27 1.27)
				)
				(justify mirror)
			)
		)
		(property "Value" "33R2F-3-GP"
			(at -0.064008 -3.993896 0)
			(unlocked yes)
			(layer "B.Fab")
			(hide yes)
			(effects
				(font
					(size 1.016 1.016)
					(thickness 0.1524)
				)
				(justify mirror)
			)
		)
		(property "Device Type" "R402H16"
			(at -0.064008 -5.517896 0)
			(unlocked yes)
			(layer "B.Fab")
			(hide yes)
			(effects
				(font
					(size 1.016 1.016)
					(thickness 0.1524)
				)
				(justify mirror)
			)
		)
		(duplicate_pad_numbers_are_jumpers no)
		(fp_rect
			(start 0.381 0.8382)
			(end -0.381 -0.8382)
			(stroke
				(width 0)
				(type default)
			)
			(fill no)
			(layer "B.CrtYd")
		)
		(fp_rect
			(start 0.381 0.8382)
			(end -0.381 -0.8382)
			(stroke
				(width 0)
				(type default)
			)
			(fill no)
			(layer "B.Fab")
		)
		(pad "1" smd custom
			(at 0 -0.4318 180)
			(size 0.127 0.127)
			(layers "B.Cu" "B.Mask" "B.Paste")
			(net "CLK_100M_CLKBUFF_SAS_R_DP")
			(options
				(clearance outline)
				(anchor circle)
			)
			(primitives
				(gr_poly
					(pts
						(arc
							(start -0.2032 0.2794)
							(mid -0.239121 0.264521)
							(end -0.254 0.2286)
						)
						(arc
							(start -0.254 -0.2286)
							(mid -0.239121 -0.264521)
							(end -0.2032 -0.2794)
						)
						(arc
							(start 0.2032 -0.2794)
							(mid 0.239121 -0.264521)
							(end 0.254 -0.2286)
						)
						(arc
							(start 0.254 0.2286)
							(mid 0.239121 0.264521)
							(end 0.2032 0.2794)
						)
					)
					(width 0)
					(fill yes)
				)
			)
		)
		(pad "2" smd custom
			(at 0 0.4318 180)
			(size 0.127 0.127)
			(layers "B.Cu" "B.Mask" "B.Paste")
			(net "CLK_100M_PCIE_SAS_DP")
			(options
				(clearance outline)
				(anchor circle)
			)
			(primitives
				(gr_poly
					(pts
						(arc
							(start -0.2032 0.2794)
							(mid -0.239121 0.264521)
							(end -0.254 0.2286)
						)
						(arc
							(start -0.254 -0.2286)
							(mid -0.239121 -0.264521)
							(end -0.2032 -0.2794)
						)
						(arc
							(start 0.2032 -0.2794)
							(mid 0.239121 -0.264521)
							(end 0.254 -0.2286)
						)
						(arc
							(start 0.254 0.2286)
							(mid 0.239121 0.264521)
							(end 0.2032 0.2794)
						)
					)
					(width 0)
					(fill yes)
				)
			)
		)
	)
	(footprint ""
		(layer "B.Cu")
		(at 74.168 -43.434 90)
		(property "Reference" "R68"
			(at 0 0 90)
			(layer "B.SilkS")
			(hide yes)
			(effects
				(font
					(size 1.27 1.27)
				)
				(justify mirror)
			)
		)
		(property "Value" "4K7R2F-GP"
			(at -0.064008 -3.993896 90)
			(unlocked yes)
			(layer "B.Fab")
			(hide yes)
			(effects
				(font
					(size 1.016 1.016)
					(thickness 0.1524)
				)
				(justify mirror)
			)
		)
		(property "Device Type" "R402H16"
			(at -0.064008 -5.517896 90)
			(unlocked yes)
			(layer "B.Fab")
			(hide yes)
			(effects
				(font
					(size 1.016 1.016)
					(thickness 0.1524)
				)
				(justify mirror)
			)
		)
		(duplicate_pad_numbers_are_jumpers no)
		(fp_rect
			(start 0.381 0.8382)
			(end -0.381 -0.8382)
			(stroke
				(width 0)
				(type default)
			)
			(fill no)
			(layer "B.CrtYd")
		)
		(fp_rect
			(start 0.381 0.8382)
			(end -0.381 -0.8382)
			(stroke
				(width 0)
				(type default)
			)
			(fill no)
			(layer "B.Fab")
		)
		(pad "1" smd custom
			(at 0 -0.4318 270)
			(size 0.127 0.127)
			(layers "B.Cu" "B.Mask" "B.Paste")
			(net "P3V3")
			(options
				(clearance outline)
				(anchor circle)
			)
			(primitives
				(gr_poly
					(pts
						(arc
							(start -0.2032 0.2794)
							(mid -0.239121 0.264521)
							(end -0.254 0.2286)
						)
						(arc
							(start -0.254 -0.2286)
							(mid -0.239121 -0.264521)
							(end -0.2032 -0.2794)
						)
						(arc
							(start 0.2032 -0.2794)
							(mid 0.239121 -0.264521)
							(end 0.254 -0.2286)
						)
						(arc
							(start 0.254 0.2286)
							(mid 0.239121 0.264521)
							(end 0.2032 0.2794)
						)
					)
					(width 0)
					(fill yes)
				)
			)
		)
		(pad "2" smd custom
			(at 0 0.4318 270)
			(size 0.127 0.127)
			(layers "B.Cu" "B.Mask" "B.Paste")
			(net "CPU_ERR_N1")
			(options
				(clearance outline)
				(anchor circle)
			)
			(primitives
				(gr_poly
					(pts
						(arc
							(start -0.2032 0.2794)
							(mid -0.239121 0.264521)
							(end -0.254 0.2286)
						)
						(arc
							(start -0.254 -0.2286)
							(mid -0.239121 -0.264521)
							(end -0.2032 -0.2794)
						)
						(arc
							(start 0.2032 -0.2794)
							(mid 0.239121 -0.264521)
							(end 0.254 -0.2286)
						)
						(arc
							(start 0.254 0.2286)
							(mid 0.239121 0.264521)
							(end 0.2032 0.2794)
						)
					)
					(width 0)
					(fill yes)
				)
			)
		)
	)
	(footprint ""
		(layer "B.Cu")
		(at 188.595 -27.94 180)
		(property "Reference" "PR212"
			(at 0 0 0)
			(layer "B.SilkS")
			(hide yes)
			(effects
				(font
					(size 1.27 1.27)
				)
				(justify mirror)
			)
		)
		(property "Value" "100R2F-L1-GP-U"
			(at -1.7907 -1.1176 180)
			(unlocked yes)
			(layer "B.Fab")
			(hide yes)
			(effects
				(font
					(size 1.016 1.016)
					(thickness 0.1524)
				)
				(justify mirror)
			)
		)
		(property "Device Type" "R402H14"
			(at -1.7907 -2.6416 180)
			(unlocked yes)
			(layer "B.Fab")
			(hide yes)
			(effects
				(font
					(size 1.016 1.016)
					(thickness 0.1524)
				)
				(justify mirror)
			)
		)
		(duplicate_pad_numbers_are_jumpers no)
		(fp_rect
			(start 0.381 0.8382)
			(end -0.381 -0.8382)
			(stroke
				(width 0)
				(type default)
			)
			(fill no)
			(layer "B.CrtYd")
		)
		(fp_rect
			(start 0.381 0.8382)
			(end -0.381 -0.8382)
			(stroke
				(width 0)
				(type default)
			)
			(fill no)
			(layer "B.Fab")
		)
		(pad "1" smd custom
			(at 0 -0.4318)
			(size 0.127 0.127)
			(layers "B.Cu" "B.Mask" "B.Paste")
			(net "VR_PVDDR_A_SUMN_C")
			(options
				(clearance outline)
				(anchor circle)
			)
			(primitives
				(gr_poly
					(pts
						(arc
							(start -0.2032 0.2794)
							(mid -0.239121 0.264521)
							(end -0.254 0.2286)
						)
						(arc
							(start -0.254 -0.2286)
							(mid -0.239121 -0.264521)
							(end -0.2032 -0.2794)
						)
						(arc
							(start 0.2032 -0.2794)
							(mid 0.239121 -0.264521)
							(end 0.254 -0.2286)
						)
						(arc
							(start 0.254 0.2286)
							(mid 0.239121 0.264521)
							(end 0.2032 0.2794)
						)
					)
					(width 0)
					(fill yes)
				)
			)
		)
		(pad "2" smd custom
			(at 0 0.4318)
			(size 0.127 0.127)
			(layers "B.Cu" "B.Mask" "B.Paste")
			(net "VR_PVDDRA_ISUMN1")
			(options
				(clearance outline)
				(anchor circle)
			)
			(primitives
				(gr_poly
					(pts
						(arc
							(start -0.2032 0.2794)
							(mid -0.239121 0.264521)
							(end -0.254 0.2286)
						)
						(arc
							(start -0.254 -0.2286)
							(mid -0.239121 -0.264521)
							(end -0.2032 -0.2794)
						)
						(arc
							(start 0.2032 -0.2794)
							(mid 0.239121 -0.264521)
							(end 0.254 -0.2286)
						)
						(arc
							(start 0.254 0.2286)
							(mid 0.239121 0.264521)
							(end 0.2032 0.2794)
						)
					)
					(width 0)
					(fill yes)
				)
			)
		)
	)
	(footprint ""
		(layer "B.Cu")
		(at 33.147 -43.688 90)
		(property "Reference" "PC137"
			(at 0 0 90)
			(layer "B.SilkS")
			(hide yes)
			(effects
				(font
					(size 1.27 1.27)
				)
				(justify mirror)
			)
		)
		(property "Value" "SC1KP50V2KX-1GP"
			(at -1.8923 -1.2065 90)
			(unlocked yes)
			(layer "B.Fab")
			(hide yes)
			(effects
				(font
					(size 1.016 1.016)
					(thickness 0.1524)
				)
				(justify mirror)
			)
		)
		(property "Device Type" "C402H22"
			(at -1.8923 -2.7305 90)
			(unlocked yes)
			(layer "B.Fab")
			(hide yes)
			(effects
				(font
					(size 1.016 1.016)
					(thickness 0.1524)
				)
				(justify mirror)
			)
		)
		(duplicate_pad_numbers_are_jumpers no)
		(fp_rect
			(start 0.381 0.7366)
			(end -0.381 -0.7366)
			(stroke
				(width 0)
				(type default)
			)
			(fill no)
			(layer "B.CrtYd")
		)
		(fp_rect
			(start 0.381 0.7366)
			(end -0.381 -0.7366)
			(stroke
				(width 0)
				(type default)
			)
			(fill no)
			(layer "B.Fab")
		)
		(pad "1" smd custom
			(at 0 -0.4572 270)
			(size 0.1143 0.1143)
			(layers "B.Cu" "B.Mask" "B.Paste")
			(net "P1V5_STBY_OUT")
			(options
				(clearance outline)
				(anchor circle)
			)
			(primitives
				(gr_poly
					(pts
						(arc
							(start -0.254 0.1778)
							(mid -0.239121 0.213721)
							(end -0.2032 0.2286)
						)
						(arc
							(start 0.2032 0.2286)
							(mid 0.239121 0.213721)
							(end 0.254 0.1778)
						)
						(arc
							(start 0.254 -0.1778)
							(mid 0.239121 -0.213721)
							(end 0.2032 -0.2286)
						)
						(arc
							(start -0.2032 -0.2286)
							(mid -0.239121 -0.213721)
							(end -0.254 -0.1778)
						)
					)
					(width 0)
					(fill yes)
				)
			)
		)
		(pad "2" smd custom
			(at 0 0.4572 270)
			(size 0.1143 0.1143)
			(layers "B.Cu" "B.Mask" "B.Paste")
			(net "P1V5_STBY_FB")
			(options
				(clearance outline)
				(anchor circle)
			)
			(primitives
				(gr_poly
					(pts
						(arc
							(start -0.254 0.1778)
							(mid -0.239121 0.213721)
							(end -0.2032 0.2286)
						)
						(arc
							(start 0.2032 0.2286)
							(mid 0.239121 0.213721)
							(end 0.254 0.1778)
						)
						(arc
							(start 0.254 -0.1778)
							(mid 0.239121 -0.213721)
							(end 0.2032 -0.2286)
						)
						(arc
							(start -0.2032 -0.2286)
							(mid -0.239121 -0.213721)
							(end -0.254 -0.1778)
						)
					)
					(width 0)
					(fill yes)
				)
			)
		)
	)
	(footprint ""
		(layer "B.Cu")
		(at 129.286 -25.273 180)
		(property "Reference" "R32"
			(at 0 0 0)
			(layer "B.SilkS")
			(hide yes)
			(effects
				(font
					(size 1.27 1.27)
				)
				(justify mirror)
			)
		)
		(property "Value" "1KR2F-3-GP"
			(at -0.064008 -3.993896 180)
			(unlocked yes)
			(layer "B.Fab")
			(hide yes)
			(effects
				(font
					(size 1.016 1.016)
					(thickness 0.1524)
				)
				(justify mirror)
			)
		)
		(property "Device Type" "R402H16"
			(at -0.064008 -5.517896 180)
			(unlocked yes)
			(layer "B.Fab")
			(hide yes)
			(effects
				(font
					(size 1.016 1.016)
					(thickness 0.1524)
				)
				(justify mirror)
			)
		)
		(duplicate_pad_numbers_are_jumpers no)
		(fp_rect
			(start 0.381 0.8382)
			(end -0.381 -0.8382)
			(stroke
				(width 0)
				(type default)
			)
			(fill no)
			(layer "B.CrtYd")
		)
		(fp_rect
			(start 0.381 0.8382)
			(end -0.381 -0.8382)
			(stroke
				(width 0)
				(type default)
			)
			(fill no)
			(layer "B.Fab")
		)
		(pad "1" smd custom
			(at 0 -0.4318)
			(size 0.127 0.127)
			(layers "B.Cu" "B.Mask" "B.Paste")
			(net "P3V3_STBY")
			(options
				(clearance outline)
				(anchor circle)
			)
			(primitives
				(gr_poly
					(pts
						(arc
							(start -0.2032 0.2794)
							(mid -0.239121 0.264521)
							(end -0.254 0.2286)
						)
						(arc
							(start -0.254 -0.2286)
							(mid -0.239121 -0.264521)
							(end -0.2032 -0.2794)
						)
						(arc
							(start 0.2032 -0.2794)
							(mid 0.239121 -0.264521)
							(end 0.254 -0.2286)
						)
						(arc
							(start 0.254 0.2286)
							(mid 0.239121 0.264521)
							(end 0.2032 0.2794)
						)
					)
					(width 0)
					(fill yes)
				)
			)
		)
		(pad "2" smd custom
			(at 0 0.4318)
			(size 0.127 0.127)
			(layers "B.Cu" "B.Mask" "B.Paste")
			(net "CPU_THERMTRIP_LVC#")
			(options
				(clearance outline)
				(anchor circle)
			)
			(primitives
				(gr_poly
					(pts
						(arc
							(start -0.2032 0.2794)
							(mid -0.239121 0.264521)
							(end -0.254 0.2286)
						)
						(arc
							(start -0.254 -0.2286)
							(mid -0.239121 -0.264521)
							(end -0.2032 -0.2794)
						)
						(arc
							(start 0.2032 -0.2794)
							(mid 0.239121 -0.264521)
							(end 0.254 -0.2286)
						)
						(arc
							(start 0.254 0.2286)
							(mid 0.239121 0.264521)
							(end 0.2032 0.2794)
						)
					)
					(width 0)
					(fill yes)
				)
			)
		)
	)
	(footprint ""
		(layer "B.Cu")
		(at 90.2081 -33.4518 90)
		(property "Reference" "C212"
			(at 0 0 90)
			(layer "B.SilkS")
			(hide yes)
			(effects
				(font
					(size 1.27 1.27)
				)
				(justify mirror)
			)
		)
		(property "Value" "SC1U10V2KX-1GP"
			(at -1.1811 -2.7051 90)
			(unlocked yes)
			(layer "B.Fab")
			(hide yes)
			(effects
				(font
					(size 1.016 1.016)
					(thickness 0.1524)
				)
				(justify mirror)
			)
		)
		(property "Device Type" "C402H22"
			(at -1.1811 -4.2291 90)
			(unlocked yes)
			(layer "B.Fab")
			(hide yes)
			(effects
				(font
					(size 1.016 1.016)
					(thickness 0.1524)
				)
				(justify mirror)
			)
		)
		(duplicate_pad_numbers_are_jumpers no)
		(fp_rect
			(start 0.381 0.7366)
			(end -0.381 -0.7366)
			(stroke
				(width 0)
				(type default)
			)
			(fill no)
			(layer "B.CrtYd")
		)
		(fp_rect
			(start 0.381 0.7366)
			(end -0.381 -0.7366)
			(stroke
				(width 0)
				(type default)
			)
			(fill no)
			(layer "B.Fab")
		)
		(pad "1" smd custom
			(at 0 -0.4572 270)
			(size 0.1143 0.1143)
			(layers "B.Cu" "B.Mask" "B.Paste")
			(net "P1V0")
			(options
				(clearance outline)
				(anchor circle)
			)
			(primitives
				(gr_poly
					(pts
						(arc
							(start -0.254 0.1778)
							(mid -0.239121 0.213721)
							(end -0.2032 0.2286)
						)
						(arc
							(start 0.2032 0.2286)
							(mid 0.239121 0.213721)
							(end 0.254 0.1778)
						)
						(arc
							(start 0.254 -0.1778)
							(mid 0.239121 -0.213721)
							(end 0.2032 -0.2286)
						)
						(arc
							(start -0.2032 -0.2286)
							(mid -0.239121 -0.213721)
							(end -0.254 -0.1778)
						)
					)
					(width 0)
					(fill yes)
				)
			)
		)
		(pad "2" smd custom
			(at 0 0.4572 270)
			(size 0.1143 0.1143)
			(layers "B.Cu" "B.Mask" "B.Paste")
			(net "GND")
			(options
				(clearance outline)
				(anchor circle)
			)
			(primitives
				(gr_poly
					(pts
						(arc
							(start -0.254 0.1778)
							(mid -0.239121 0.213721)
							(end -0.2032 0.2286)
						)
						(arc
							(start 0.2032 0.2286)
							(mid 0.239121 0.213721)
							(end 0.254 0.1778)
						)
						(arc
							(start 0.254 -0.1778)
							(mid 0.239121 -0.213721)
							(end 0.2032 -0.2286)
						)
						(arc
							(start -0.2032 -0.2286)
							(mid -0.239121 -0.213721)
							(end -0.254 -0.1778)
						)
					)
					(width 0)
					(fill yes)
				)
			)
		)
	)
)
